(kicad_pcb
	(version 20260206)
	(generator "pcbnew")
	(generator_version "10.0")
	(general
		(thickness 1.6)
		(legacy_teardrops no)
	)
	(paper "A4")
	(title_block
		(title "01162023_DA0F0TEBIF0_F0T_Expander_BD_F_brd_V02_OCP.brd")
		(comment 1 "Grand Teton / footprints 9161-9168 of 9728")
	)
	(layers
		(0 "F.Cu" signal "TOP")
		(4 "In1.Cu" signal "GND")
		(6 "In2.Cu" signal "VCC")
		(8 "In3.Cu" signal "VCC1")
		(10 "In4.Cu" signal "GND1")
		(12 "In5.Cu" signal "IN1")
		(14 "In6.Cu" signal "GND2")
		(16 "In7.Cu" signal "IN2")
		(18 "In8.Cu" signal "GND3")
		(20 "In9.Cu" signal "IN3")
		(22 "In10.Cu" signal "GND4")
		(24 "In11.Cu" signal "IN4")
		(26 "In12.Cu" signal "GND5")
		(28 "In13.Cu" signal "IN5")
		(30 "In14.Cu" signal "GND6")
		(32 "In15.Cu" signal "IN6")
		(34 "In16.Cu" signal "GND7")
		(2 "B.Cu" signal "BOTTOM")
		(9 "F.Adhes" user "F.Adhesive")
		(11 "B.Adhes" user "B.Adhesive")
		(13 "F.Paste" user "Package Geometry/Pastemask Top")
		(15 "B.Paste" user "Package Geometry/Pastemask Bottom")
		(5 "F.SilkS" user "Ref Des/Silkscreen Top")
		(7 "B.SilkS" user "Ref Des/Silkscreen Bottom")
		(1 "F.Mask" user "Board Geometry/Soldermask Top")
		(3 "B.Mask" user "Board Geometry/Soldermask Bottom")
		(17 "Dwgs.User" user "User.Drawings")
		(19 "Cmts.User" user "User.Comments")
		(21 "Eco1.User" user "User.Eco1")
		(23 "Eco2.User" user "User.Eco2")
		(25 "Edge.Cuts" user "Board Geometry/Outline")
		(27 "Margin" user)
		(31 "F.CrtYd" user "Package Geometry/Place Bound Top")
		(29 "B.CrtYd" user "Package Geometry/Place Bound Bottom")
		(35 "F.Fab" user "Ref Des/Assembly Top")
		(33 "B.Fab" user "Ref Des/Assembly Bottom")
	)
	(footprint ""
		(layer "B.Cu")
		(at 227.067618 -217.504264 180)
		(property "Reference" "C2009"
			(at 0 0 0)
			(layer "B.SilkS")
			(hide yes)
			(effects
				(font
					(size 1.27 1.27)
				)
				(justify mirror)
			)
		)
		(property "Value" ""
			(at 0 0 0)
			(layer "B.Fab")
			(effects
				(font
					(size 1.27 1.27)
				)
				(justify mirror)
			)
		)
		(duplicate_pad_numbers_are_jumpers no)
		(fp_line
			(start 0.69215 0.2921)
			(end 0.69215 -0.2921)
			(stroke
				(width 0.1524)
				(type default)
			)
			(layer "B.SilkS")
		)
		(fp_line
			(start 0.69215 -0.2921)
			(end -0.69215 -0.2921)
			(stroke
				(width 0.1524)
				(type default)
			)
			(layer "B.SilkS")
		)
		(fp_line
			(start -0.69215 0.2921)
			(end 0.69215 0.2921)
			(stroke
				(width 0.1524)
				(type default)
			)
			(layer "B.SilkS")
		)
		(fp_line
			(start -0.69215 -0.2921)
			(end -0.69215 0.2921)
			(stroke
				(width 0.1524)
				(type default)
			)
			(layer "B.SilkS")
		)
		(fp_line
			(start 0.51435 0.2794)
			(end 0.51435 -0.2794)
			(stroke
				(width 0.1)
				(type default)
			)
			(layer "B.Fab")
		)
		(fp_line
			(start 0.51435 -0.2794)
			(end -0.51435 -0.2794)
			(stroke
				(width 0.1)
				(type default)
			)
			(layer "B.Fab")
		)
		(fp_line
			(start -0.51435 0.2794)
			(end 0.51435 0.2794)
			(stroke
				(width 0.1)
				(type default)
			)
			(layer "B.Fab")
		)
		(fp_line
			(start -0.51435 -0.2794)
			(end -0.51435 0.2794)
			(stroke
				(width 0.1)
				(type default)
			)
			(layer "B.Fab")
		)
		(pad "1" smd circle
			(at 0.40005 0)
			(size 0 0)
			(layers "B.Cu" "B.Mask" "B.Paste")
			(net "P3V3_AUX")
		)
		(pad "2" smd circle
			(at -0.40005 0)
			(size 0 0)
			(layers "B.Cu" "B.Mask" "B.Paste")
			(net "GND")
		)
		(zone
			(layer "B.Cu")
			(hatch none 0.5)
			(connect_pads
				(clearance 0)
			)
			(min_thickness 0.25)
			(keepout
				(tracks not_allowed)
				(vias allowed)
				(pads allowed)
				(copperpour not_allowed)
				(footprints allowed)
			)
			(placement
				(enabled no)
				(sheetname "")
			)
			(fill
				(thermal_gap 0.5)
				(thermal_bridge_width 0.5)
				(island_removal_mode 0)
			)
			(polygon
				(pts
					(xy 226.877118 -217.591894) (xy 226.968558 -217.65006) (xy 227.167948 -217.65006) (xy 227.258118 -217.591894)
					(xy 227.258118 -217.416634) (xy 227.167948 -217.358214) (xy 226.968558 -217.358214) (xy 226.877118 -217.41638)
				)
			)
		)
	)
	(footprint ""
		(layer "B.Cu")
		(at 234.718098 -274.274534)
		(property "Reference" "C4347"
			(at 0 0 0)
			(layer "B.SilkS")
			(hide yes)
			(effects
				(font
					(size 1.27 1.27)
				)
				(justify mirror)
			)
		)
		(property "Value" ""
			(at 0 0 0)
			(layer "B.Fab")
			(effects
				(font
					(size 1.27 1.27)
				)
				(justify mirror)
			)
		)
		(duplicate_pad_numbers_are_jumpers no)
		(fp_line
			(start -1.2954 -0.5842)
			(end -1.2954 0.5842)
			(stroke
				(width 0.1524)
				(type default)
			)
			(layer "B.SilkS")
		)
		(fp_line
			(start -1.2954 0.5842)
			(end 1.2954 0.5842)
			(stroke
				(width 0.1524)
				(type default)
			)
			(layer "B.SilkS")
		)
		(fp_line
			(start 1.2954 -0.5842)
			(end -1.2954 -0.5842)
			(stroke
				(width 0.1524)
				(type default)
			)
			(layer "B.SilkS")
		)
		(fp_line
			(start 1.2954 0.5842)
			(end 1.2954 -0.5842)
			(stroke
				(width 0.1524)
				(type default)
			)
			(layer "B.SilkS")
		)
		(fp_line
			(start -1.1938 -0.4064)
			(end -1.1938 0.4064)
			(stroke
				(width 0.1)
				(type default)
			)
			(layer "B.Fab")
		)
		(fp_line
			(start -1.1938 0.4064)
			(end -0.8636 0.4064)
			(stroke
				(width 0.1)
				(type default)
			)
			(layer "B.Fab")
		)
		(fp_line
			(start -0.8636 -0.4572)
			(end -0.8636 -0.4064)
			(stroke
				(width 0.1)
				(type default)
			)
			(layer "B.Fab")
		)
		(fp_line
			(start -0.8636 -0.4064)
			(end -1.1938 -0.4064)
			(stroke
				(width 0.1)
				(type default)
			)
			(layer "B.Fab")
		)
		(fp_line
			(start -0.8636 0.4064)
			(end -0.8636 0.4572)
			(stroke
				(width 0.1)
				(type default)
			)
			(layer "B.Fab")
		)
		(fp_line
			(start -0.8636 0.4572)
			(end 0.8636 0.4572)
			(stroke
				(width 0.1)
				(type default)
			)
			(layer "B.Fab")
		)
		(fp_line
			(start 0.8636 -0.4572)
			(end -0.8636 -0.4572)
			(stroke
				(width 0.1)
				(type default)
			)
			(layer "B.Fab")
		)
		(fp_line
			(start 0.8636 -0.4064)
			(end 0.8636 -0.4572)
			(stroke
				(width 0.1)
				(type default)
			)
			(layer "B.Fab")
		)
		(fp_line
			(start 0.8636 0.4064)
			(end 1.1938 0.4064)
			(stroke
				(width 0.1)
				(type default)
			)
			(layer "B.Fab")
		)
		(fp_line
			(start 0.8636 0.4572)
			(end 0.8636 0.4064)
			(stroke
				(width 0.1)
				(type default)
			)
			(layer "B.Fab")
		)
		(fp_line
			(start 1.1938 -0.4064)
			(end 0.8636 -0.4064)
			(stroke
				(width 0.1)
				(type default)
			)
			(layer "B.Fab")
		)
		(fp_line
			(start 1.1938 0.4064)
			(end 1.1938 -0.4064)
			(stroke
				(width 0.1)
				(type default)
			)
			(layer "B.Fab")
		)
		(pad "1" smd rect
			(at 0.7366 0 270)
			(size 0.7112 0.8128)
			(layers "B.Cu" "B.Mask" "B.Paste")
			(net "P1V25_PEX2")
		)
		(pad "2" smd rect
			(at -0.7366 0 270)
			(size 0.7112 0.8128)
			(layers "B.Cu" "B.Mask" "B.Paste")
			(net "GND")
		)
	)
	(footprint ""
		(layer "B.Cu")
		(at 182.39994 -292.099746 90)
		(property "Reference" "C1441"
			(at 0 0 90)
			(layer "B.SilkS")
			(hide yes)
			(effects
				(font
					(size 1.27 1.27)
				)
				(justify mirror)
			)
		)
		(property "Value" ""
			(at 0 0 90)
			(layer "B.Fab")
			(effects
				(font
					(size 1.27 1.27)
				)
				(justify mirror)
			)
		)
		(duplicate_pad_numbers_are_jumpers no)
		(fp_line
			(start 0.299974 -0.150114)
			(end -0.299974 -0.150114)
			(stroke
				(width 0.1)
				(type default)
			)
			(layer "B.Fab")
		)
		(fp_line
			(start -0.299974 -0.150114)
			(end -0.299974 0.150114)
			(stroke
				(width 0.1)
				(type default)
			)
			(layer "B.Fab")
		)
		(fp_line
			(start 0.299974 0.150114)
			(end 0.299974 -0.150114)
			(stroke
				(width 0.1)
				(type default)
			)
			(layer "B.Fab")
		)
		(fp_line
			(start -0.299974 0.150114)
			(end 0.299974 0.150114)
			(stroke
				(width 0.1)
				(type default)
			)
			(layer "B.Fab")
		)
		(pad "1" smd rect
			(at 0.2667 0 270)
			(size 0.3048 0.381)
			(layers "B.Cu" "B.Mask" "B.Paste")
			(net "P0V8_SERDES_VDDA_PEX1")
		)
		(pad "2" smd rect
			(at -0.2667 0 270)
			(size 0.3048 0.381)
			(layers "B.Cu" "B.Mask" "B.Paste")
			(net "GND")
		)
	)
	(footprint ""
		(layer "B.Cu")
		(at 288.049716 -290.199826 90)
		(property "Reference" "C1741"
			(at 0 0 90)
			(layer "B.SilkS")
			(hide yes)
			(effects
				(font
					(size 1.27 1.27)
				)
				(justify mirror)
			)
		)
		(property "Value" ""
			(at 0 0 90)
			(layer "B.Fab")
			(effects
				(font
					(size 1.27 1.27)
				)
				(justify mirror)
			)
		)
		(duplicate_pad_numbers_are_jumpers no)
		(fp_line
			(start 0.299974 -0.150114)
			(end -0.299974 -0.150114)
			(stroke
				(width 0.1)
				(type default)
			)
			(layer "B.Fab")
		)
		(fp_line
			(start -0.299974 -0.150114)
			(end -0.299974 0.150114)
			(stroke
				(width 0.1)
				(type default)
			)
			(layer "B.Fab")
		)
		(fp_line
			(start 0.299974 0.150114)
			(end 0.299974 -0.150114)
			(stroke
				(width 0.1)
				(type default)
			)
			(layer "B.Fab")
		)
		(fp_line
			(start -0.299974 0.150114)
			(end 0.299974 0.150114)
			(stroke
				(width 0.1)
				(type default)
			)
			(layer "B.Fab")
		)
		(pad "1" smd rect
			(at 0.2667 0 270)
			(size 0.3048 0.381)
			(layers "B.Cu" "B.Mask" "B.Paste")
			(net "P0V8_SERDES_VDDA_PEX2")
		)
		(pad "2" smd rect
			(at -0.2667 0 270)
			(size 0.3048 0.381)
			(layers "B.Cu" "B.Mask" "B.Paste")
			(net "GND")
		)
	)
	(footprint ""
		(layer "B.Cu")
		(at 346.093796 -213.187026 90)
		(property "Reference" "C2050"
			(at 0 0 90)
			(layer "B.SilkS")
			(hide yes)
			(effects
				(font
					(size 1.27 1.27)
				)
				(justify mirror)
			)
		)
		(property "Value" ""
			(at 0 0 90)
			(layer "B.Fab")
			(effects
				(font
					(size 1.27 1.27)
				)
				(justify mirror)
			)
		)
		(duplicate_pad_numbers_are_jumpers no)
		(fp_line
			(start 0.69215 -0.2921)
			(end -0.69215 -0.2921)
			(stroke
				(width 0.1524)
				(type default)
			)
			(layer "B.SilkS")
		)
		(fp_line
			(start -0.69215 -0.2921)
			(end -0.69215 0.2921)
			(stroke
				(width 0.1524)
				(type default)
			)
			(layer "B.SilkS")
		)
		(fp_line
			(start 0.69215 0.2921)
			(end 0.69215 -0.2921)
			(stroke
				(width 0.1524)
				(type default)
			)
			(layer "B.SilkS")
		)
		(fp_line
			(start -0.69215 0.2921)
			(end 0.69215 0.2921)
			(stroke
				(width 0.1524)
				(type default)
			)
			(layer "B.SilkS")
		)
		(fp_line
			(start 0.51435 -0.2794)
			(end -0.51435 -0.2794)
			(stroke
				(width 0.1)
				(type default)
			)
			(layer "B.Fab")
		)
		(fp_line
			(start -0.51435 -0.2794)
			(end -0.51435 0.2794)
			(stroke
				(width 0.1)
				(type default)
			)
			(layer "B.Fab")
		)
		(fp_line
			(start 0.51435 0.2794)
			(end 0.51435 -0.2794)
			(stroke
				(width 0.1)
				(type default)
			)
			(layer "B.Fab")
		)
		(fp_line
			(start -0.51435 0.2794)
			(end 0.51435 0.2794)
			(stroke
				(width 0.1)
				(type default)
			)
			(layer "B.Fab")
		)
		(pad "1" smd circle
			(at 0.40005 0 270)
			(size 0 0)
			(layers "B.Cu" "B.Mask" "B.Paste")
			(net "P3V3_FPGA_VCCIO2")
		)
		(pad "2" smd circle
			(at -0.40005 0 270)
			(size 0 0)
			(layers "B.Cu" "B.Mask" "B.Paste")
			(net "GND")
		)
		(zone
			(layer "B.Cu")
			(hatch none 0.5)
			(connect_pads
				(clearance 0)
			)
			(min_thickness 0.25)
			(keepout
				(tracks not_allowed)
				(vias allowed)
				(pads allowed)
				(copperpour not_allowed)
				(footprints allowed)
			)
			(placement
				(enabled no)
				(sheetname "")
			)
			(fill
				(thermal_gap 0.5)
				(thermal_bridge_width 0.5)
				(island_removal_mode 0)
			)
			(polygon
				(pts
					(xy 346.181426 -213.377526) (xy 346.239592 -213.286086) (xy 346.239592 -213.086696) (xy 346.181426 -212.996526)
					(xy 346.006166 -212.996526) (xy 345.947746 -213.086696) (xy 345.947746 -213.286086) (xy 346.005912 -213.377526)
				)
			)
		)
	)
	(footprint ""
		(layer "B.Cu")
		(at 300.425866 -246.441722 90)
		(property "Reference" "R4100"
			(at 0 0 90)
			(layer "B.SilkS")
			(hide yes)
			(effects
				(font
					(size 1.27 1.27)
				)
				(justify mirror)
			)
		)
		(property "Value" ""
			(at 0 0 90)
			(layer "B.Fab")
			(effects
				(font
					(size 1.27 1.27)
				)
				(justify mirror)
			)
		)
		(duplicate_pad_numbers_are_jumpers no)
		(fp_line
			(start 0.7874 -0.4064)
			(end -0.7874 -0.4064)
			(stroke
				(width 0.1524)
				(type default)
			)
			(layer "B.SilkS")
		)
		(fp_line
			(start -0.7874 -0.4064)
			(end -0.7874 0.4064)
			(stroke
				(width 0.1524)
				(type default)
			)
			(layer "B.SilkS")
		)
		(fp_line
			(start 0.7874 0.4064)
			(end 0.7874 -0.4064)
			(stroke
				(width 0.1524)
				(type default)
			)
			(layer "B.SilkS")
		)
		(fp_line
			(start -0.7874 0.4064)
			(end 0.7874 0.4064)
			(stroke
				(width 0.1524)
				(type default)
			)
			(layer "B.SilkS")
		)
		(fp_line
			(start 0.67945 -0.305054)
			(end 0.12065 -0.305054)
			(stroke
				(width 0.1)
				(type default)
			)
			(layer "B.Fab")
		)
		(fp_line
			(start 0.12065 -0.305054)
			(end 0.12065 -0.2794)
			(stroke
				(width 0.1)
				(type default)
			)
			(layer "B.Fab")
		)
		(fp_line
			(start -0.12065 -0.3048)
			(end -0.67945 -0.3048)
			(stroke
				(width 0.1)
				(type default)
			)
			(layer "B.Fab")
		)
		(fp_line
			(start -0.67945 -0.3048)
			(end -0.67945 0.3048)
			(stroke
				(width 0.1)
				(type default)
			)
			(layer "B.Fab")
		)
		(fp_line
			(start 0.12065 -0.2794)
			(end -0.12065 -0.2794)
			(stroke
				(width 0.1)
				(type default)
			)
			(layer "B.Fab")
		)
		(fp_line
			(start -0.12065 -0.2794)
			(end -0.12065 -0.3048)
			(stroke
				(width 0.1)
				(type default)
			)
			(layer "B.Fab")
		)
		(fp_line
			(start 0.12065 0.2794)
			(end 0.12065 0.3048)
			(stroke
				(width 0.1)
				(type default)
			)
			(layer "B.Fab")
		)
		(fp_line
			(start -0.120396 0.2794)
			(end 0.12065 0.2794)
			(stroke
				(width 0.1)
				(type default)
			)
			(layer "B.Fab")
		)
		(fp_line
			(start 0.67945 0.3048)
			(end 0.67945 -0.305054)
			(stroke
				(width 0.1)
				(type default)
			)
			(layer "B.Fab")
		)
		(fp_line
			(start 0.12065 0.3048)
			(end 0.67945 0.3048)
			(stroke
				(width 0.1)
				(type default)
			)
			(layer "B.Fab")
		)
		(fp_line
			(start -0.120396 0.3048)
			(end -0.120396 0.2794)
			(stroke
				(width 0.1)
				(type default)
			)
			(layer "B.Fab")
		)
		(fp_line
			(start -0.67945 0.3048)
			(end -0.120396 0.3048)
			(stroke
				(width 0.1)
				(type default)
			)
			(layer "B.Fab")
		)
		(pad "1" smd circle
			(at 0.40005 0 270)
			(size 0 0)
			(layers "B.Cu" "B.Mask" "B.Paste")
			(net "MB_I2C_ISO_EN")
		)
		(pad "2" smd circle
			(at -0.40005 0 270)
			(size 0 0)
			(layers "B.Cu" "B.Mask" "B.Paste")
			(net "P3V3_AUX")
		)
	)
	(footprint ""
		(layer "B.Cu")
		(at 418.40404 -97.663)
		(property "Reference" "R361"
			(at 0 0 0)
			(layer "B.SilkS")
			(hide yes)
			(effects
				(font
					(size 1.27 1.27)
				)
				(justify mirror)
			)
		)
		(property "Value" ""
			(at 0 0 0)
			(layer "B.Fab")
			(effects
				(font
					(size 1.27 1.27)
				)
				(justify mirror)
			)
		)
		(duplicate_pad_numbers_are_jumpers no)
		(fp_line
			(start -0.7874 -0.4064)
			(end -0.7874 0.4064)
			(stroke
				(width 0.1524)
				(type default)
			)
			(layer "B.SilkS")
		)
		(fp_line
			(start -0.7874 0.4064)
			(end 0.7874 0.4064)
			(stroke
				(width 0.1524)
				(type default)
			)
			(layer "B.SilkS")
		)
		(fp_line
			(start 0.7874 -0.4064)
			(end -0.7874 -0.4064)
			(stroke
				(width 0.1524)
				(type default)
			)
			(layer "B.SilkS")
		)
		(fp_line
			(start 0.7874 0.4064)
			(end 0.7874 -0.4064)
			(stroke
				(width 0.1524)
				(type default)
			)
			(layer "B.SilkS")
		)
		(fp_line
			(start -0.67945 -0.3048)
			(end -0.67945 0.3048)
			(stroke
				(width 0.1)
				(type default)
			)
			(layer "B.Fab")
		)
		(fp_line
			(start -0.67945 0.3048)
			(end -0.120396 0.3048)
			(stroke
				(width 0.1)
				(type default)
			)
			(layer "B.Fab")
		)
		(fp_line
			(start -0.12065 -0.3048)
			(end -0.67945 -0.3048)
			(stroke
				(width 0.1)
				(type default)
			)
			(layer "B.Fab")
		)
		(fp_line
			(start -0.12065 -0.2794)
			(end -0.12065 -0.3048)
			(stroke
				(width 0.1)
				(type default)
			)
			(layer "B.Fab")
		)
		(fp_line
			(start -0.120396 0.2794)
			(end 0.12065 0.2794)
			(stroke
				(width 0.1)
				(type default)
			)
			(layer "B.Fab")
		)
		(fp_line
			(start -0.120396 0.3048)
			(end -0.120396 0.2794)
			(stroke
				(width 0.1)
				(type default)
			)
			(layer "B.Fab")
		)
		(fp_line
			(start 0.12065 -0.305054)
			(end 0.12065 -0.2794)
			(stroke
				(width 0.1)
				(type default)
			)
			(layer "B.Fab")
		)
		(fp_line
			(start 0.12065 -0.2794)
			(end -0.12065 -0.2794)
			(stroke
				(width 0.1)
				(type default)
			)
			(layer "B.Fab")
		)
		(fp_line
			(start 0.12065 0.2794)
			(end 0.12065 0.3048)
			(stroke
				(width 0.1)
				(type default)
			)
			(layer "B.Fab")
		)
		(fp_line
			(start 0.12065 0.3048)
			(end 0.67945 0.3048)
			(stroke
				(width 0.1)
				(type default)
			)
			(layer "B.Fab")
		)
		(fp_line
			(start 0.67945 -0.305054)
			(end 0.12065 -0.305054)
			(stroke
				(width 0.1)
				(type default)
			)
			(layer "B.Fab")
		)
		(fp_line
			(start 0.67945 0.3048)
			(end 0.67945 -0.305054)
			(stroke
				(width 0.1)
				(type default)
			)
			(layer "B.Fab")
		)
		(pad "1" smd circle
			(at 0.40005 0 180)
			(size 0 0)
			(layers "B.Cu" "B.Mask" "B.Paste")
			(net "PWRGD_NIC7_PWR_GOOD")
		)
		(pad "2" smd circle
			(at -0.40005 0 180)
			(size 0 0)
			(layers "B.Cu" "B.Mask" "B.Paste")
			(net "PWRGD_NIC7_PWR_GOOD_R")
		)
	)
	(footprint ""
		(layer "B.Cu")
		(at 406.049988 -288.299906 90)
		(property "Reference" "C3458"
			(at 0 0 90)
			(layer "B.SilkS")
			(hide yes)
			(effects
				(font
					(size 1.27 1.27)
				)
				(justify mirror)
			)
		)
		(property "Value" ""
			(at 0 0 90)
			(layer "B.Fab")
			(effects
				(font
					(size 1.27 1.27)
				)
				(justify mirror)
			)
		)
		(duplicate_pad_numbers_are_jumpers no)
		(fp_line
			(start 0.299974 -0.150114)
			(end -0.299974 -0.150114)
			(stroke
				(width 0.1)
				(type default)
			)
			(layer "B.Fab")
		)
		(fp_line
			(start -0.299974 -0.150114)
			(end -0.299974 0.150114)
			(stroke
				(width 0.1)
				(type default)
			)
			(layer "B.Fab")
		)
		(fp_line
			(start 0.299974 0.150114)
			(end 0.299974 -0.150114)
			(stroke
				(width 0.1)
				(type default)
			)
			(layer "B.Fab")
		)
		(fp_line
			(start -0.299974 0.150114)
			(end 0.299974 0.150114)
			(stroke
				(width 0.1)
				(type default)
			)
			(layer "B.Fab")
		)
		(pad "1" smd rect
			(at 0.2667 0 270)
			(size 0.3048 0.381)
			(layers "B.Cu" "B.Mask" "B.Paste")
			(net "P1V25_PEX3")
		)
		(pad "2" smd rect
			(at -0.2667 0 270)
			(size 0.3048 0.381)
			(layers "B.Cu" "B.Mask" "B.Paste")
			(net "GND")
		)
	)
)
